FILE_TYPE = CONNECTIVITY;
{Allegro Design Entry HDL 17.4-2019 S026 (4007227) 1/17/2022}
"PAGE_NUMBER" = 247;
0"NC";
END.
